# T6G (Grand Teton) — schematic netlist excerpt (pin names and nets, part order shuffled) for the footprints in the layout excerpt that follows; sources: Cadence DE-HDL packaged netlist, KiCad conversion of 04192023_DAF0TMB3IC0_F0TG_MB_C_brd_V02_OCP.brd

U45  PI3CSW12ZUAEX  IC  pkg UQFN10_0-5_2X1-5  page 186
  \1d+\  = SMB_RT_CPU1_P0_ROM_MUX_1D_SCL
  \1d-\  = SMB_RT_CPU1_P0_ROM_MUX_1D_SDA
  \2d+\  = SMB_RT_CPU1_P0_ROM_MUX_2D_SCL
  \2d-\  = SMB_RT_CPU1_P0_ROM_MUX_2D_SDA
  GND  = GND
  \oe#\  = RT_ROM_MUX1_OE_N
  \d-\  = SMB_RT_CPU1_P0_ROM_R_SDA
  \d+\  = SMB_RT_CPU1_P0_ROM_R_SCL
  S  = FM_SMB_RT_ROM_MUX1_SEL
  VDD  = P3V3_AUX

C1979  Q_CAP  0.1UF 25V 10% X7R  pkg 0402  page 129 : A = P3V3_AUX ; B = GND

(kicad_pcb
	(version 20260206)
	(generator "pcbnew")
	(generator_version "10.0")
	(general
		(thickness 1.6)
		(legacy_teardrops no)
	)
	(paper "A4")
	(title_block
		(title "04192023_DAF0TMB3IC0_F0TG_MB_C_brd_V02_OCP.brd")
		(comment 1 "Grand Teton / footprints 1482-1483 of 8354")
	)
	(layers
		(0 "F.Cu" signal "TOP")
		(4 "In1.Cu" signal "GND")
		(6 "In2.Cu" signal "IN1")
		(8 "In3.Cu" signal "GND1")
		(10 "In4.Cu" signal "IN2")
		(12 "In5.Cu" signal "GND2")
		(14 "In6.Cu" signal "IN3")
		(16 "In7.Cu" signal "GND3")
		(18 "In8.Cu" signal "VCC")
		(20 "In9.Cu" signal "VCC1")
		(22 "In10.Cu" signal "GND4")
		(24 "In11.Cu" signal "IN4")
		(26 "In12.Cu" signal "GND5")
		(28 "In13.Cu" signal "IN5")
		(30 "In14.Cu" signal "GND6")
		(32 "In15.Cu" signal "IN6")
		(34 "In16.Cu" signal "GND7")
		(2 "B.Cu" signal "BOTTOM")
		(9 "F.Adhes" user "F.Adhesive")
		(11 "B.Adhes" user "B.Adhesive")
		(13 "F.Paste" user "Package Geometry/Pastemask Top")
		(15 "B.Paste" user "Package Geometry/Pastemask Bottom")
		(5 "F.SilkS" user "Ref Des/Silkscreen Top")
		(7 "B.SilkS" user "Ref Des/Silkscreen Bottom")
		(1 "F.Mask" user "Board Geometry/Soldermask Top")
		(3 "B.Mask" user "Board Geometry/Soldermask Bottom")
		(17 "Dwgs.User" user "User.Drawings")
		(19 "Cmts.User" user "User.Comments")
		(21 "Eco1.User" user "User.Eco1")
		(23 "Eco2.User" user "User.Eco2")
		(25 "Edge.Cuts" user "Board Geometry/Outline")
		(27 "Margin" user)
		(31 "F.CrtYd" user "Package Geometry/Place Bound Top")
		(29 "B.CrtYd" user "Package Geometry/Place Bound Bottom")
		(35 "F.Fab" user "Ref Des/Assembly Top")
		(33 "B.Fab" user "Ref Des/Assembly Bottom")
	)
	(footprint ""
		(layer "F.Cu")
		(at 118.999 -435.102 -90)
		(property "Reference" "C1979"
			(at 0 0 270)
			(layer "F.SilkS")
			(hide yes)
			(effects
				(font
					(size 1.27 1.27)
				)
			)
		)
		(property "Value" ""
			(at 0 0 270)
			(layer "F.Fab")
			(effects
				(font
					(size 1.27 1.27)
				)
			)
		)
		(duplicate_pad_numbers_are_jumpers no)
		(fp_line
			(start -0.7874 0.4064)
			(end -0.7874 -0.4064)
			(stroke
				(width 0.1524)
				(type default)
			)
			(layer "F.SilkS")
		)
		(fp_line
			(start 0.7874 0.4064)
			(end -0.7874 0.4064)
			(stroke
				(width 0.1524)
				(type default)
			)
			(layer "F.SilkS")
		)
		(fp_line
			(start -0.7874 -0.4064)
			(end 0.7874 -0.4064)
			(stroke
				(width 0.1524)
				(type default)
			)
			(layer "F.SilkS")
		)
		(fp_line
			(start 0.7874 -0.4064)
			(end 0.7874 0.4064)
			(stroke
				(width 0.1524)
				(type default)
			)
			(layer "F.SilkS")
		)
		(fp_line
			(start -0.67945 0.3048)
			(end -0.67945 -0.305054)
			(stroke
				(width 0.1)
				(type default)
			)
			(layer "F.Fab")
		)
		(fp_line
			(start -0.12065 0.3048)
			(end -0.67945 0.3048)
			(stroke
				(width 0.1)
				(type default)
			)
			(layer "F.Fab")
		)
		(fp_line
			(start 0.120396 0.3048)
			(end 0.120396 0.2794)
			(stroke
				(width 0.1)
				(type default)
			)
			(layer "F.Fab")
		)
		(fp_line
			(start 0.67945 0.3048)
			(end 0.120396 0.3048)
			(stroke
				(width 0.1)
				(type default)
			)
			(layer "F.Fab")
		)
		(fp_line
			(start -0.12065 0.2794)
			(end -0.12065 0.3048)
			(stroke
				(width 0.1)
				(type default)
			)
			(layer "F.Fab")
		)
		(fp_line
			(start 0.120396 0.2794)
			(end -0.12065 0.2794)
			(stroke
				(width 0.1)
				(type default)
			)
			(layer "F.Fab")
		)
		(fp_line
			(start -0.12065 -0.2794)
			(end 0.12065 -0.2794)
			(stroke
				(width 0.1)
				(type default)
			)
			(layer "F.Fab")
		)
		(fp_line
			(start 0.12065 -0.2794)
			(end 0.12065 -0.3048)
			(stroke
				(width 0.1)
				(type default)
			)
			(layer "F.Fab")
		)
		(fp_line
			(start 0.12065 -0.3048)
			(end 0.67945 -0.3048)
			(stroke
				(width 0.1)
				(type default)
			)
			(layer "F.Fab")
		)
		(fp_line
			(start 0.67945 -0.3048)
			(end 0.67945 0.3048)
			(stroke
				(width 0.1)
				(type default)
			)
			(layer "F.Fab")
		)
		(fp_line
			(start -0.67945 -0.305054)
			(end -0.12065 -0.305054)
			(stroke
				(width 0.1)
				(type default)
			)
			(layer "F.Fab")
		)
		(fp_line
			(start -0.12065 -0.305054)
			(end -0.12065 -0.2794)
			(stroke
				(width 0.1)
				(type default)
			)
			(layer "F.Fab")
		)
		(pad "1" smd circle
			(at -0.40005 0 270)
			(size 0 0)
			(layers "F.Cu" "F.Mask" "F.Paste")
			(net "P3V3_AUX")
		)
		(pad "2" smd circle
			(at 0.40005 0 270)
			(size 0 0)
			(layers "F.Cu" "F.Mask" "F.Paste")
			(net "GND")
		)
	)
	(footprint ""
		(layer "F.Cu")
		(at 97.230438 -402.391626)
		(property "Reference" "U45"
			(at -0.31623 -3.169158 0)
			(unlocked yes)
			(layer "F.SilkS")
			(effects
				(font
					(size 0.7874 0.5842)
					(thickness 0.1524)
				)
			)
		)
		(property "Value" ""
			(at 0 0 0)
			(layer "F.Fab")
			(effects
				(font
					(size 1.27 1.27)
				)
			)
		)
		(duplicate_pad_numbers_are_jumpers no)
		(fp_line
			(start -1.03378 -1.284478)
			(end 1.03378 -1.284478)
			(stroke
				(width 0.1524)
				(type default)
			)
			(layer "F.SilkS")
		)
		(fp_line
			(start -1.03378 1.284478)
			(end -1.03378 -1.284478)
			(stroke
				(width 0.1524)
				(type default)
			)
			(layer "F.SilkS")
		)
		(fp_line
			(start 1.03378 -1.284478)
			(end 1.03378 1.284478)
			(stroke
				(width 0.1524)
				(type default)
			)
			(layer "F.SilkS")
		)
		(fp_line
			(start 1.03378 1.284478)
			(end -1.03378 1.284478)
			(stroke
				(width 0.1524)
				(type default)
			)
			(layer "F.SilkS")
		)
		(fp_poly
			(pts
				(xy -1.335278 -1.324102) (xy -2.011426 -1.305306) (xy -1.756156 -1.853692)
			)
			(stroke
				(width 0)
				(type default)
			)
			(fill yes)
			(layer "F.SilkS")
		)
		(fp_line
			(start -0.774954 -1.02489)
			(end 0.774954 -1.02489)
			(stroke
				(width 0.1)
				(type default)
			)
			(layer "F.Fab")
		)
		(fp_line
			(start -0.774954 1.02489)
			(end -0.774954 -1.02489)
			(stroke
				(width 0.1)
				(type default)
			)
			(layer "F.Fab")
		)
		(fp_line
			(start 0.774954 -1.02489)
			(end 0.774954 1.02489)
			(stroke
				(width 0.1)
				(type default)
			)
			(layer "F.Fab")
		)
		(fp_line
			(start 0.774954 1.02489)
			(end -0.774954 1.02489)
			(stroke
				(width 0.1)
				(type default)
			)
			(layer "F.Fab")
		)
		(fp_poly
			(pts
				(xy -1.201674 -0.750062) (xy -1.806702 -0.447548) (xy -1.806702 -1.052576)
			)
			(stroke
				(width 0)
				(type default)
			)
			(fill yes)
			(layer "F.Fab")
		)
		(pad "1" smd rect
			(at -0.64008 -0.750062 90)
			(size 0.3048 0.5334)
			(layers "F.Cu" "F.Mask" "F.Paste")
			(net "SMB_RT_CPU1_P0_ROM_MUX_1D_SCL")
		)
		(pad "2" smd rect
			(at -0.64008 -0.249936 90)
			(size 0.254 0.5334)
			(layers "F.Cu" "F.Mask" "F.Paste")
			(net "SMB_RT_CPU1_P0_ROM_MUX_1D_SDA")
		)
		(pad "3" smd rect
			(at -0.64008 0.249936 90)
			(size 0.254 0.5334)
			(layers "F.Cu" "F.Mask" "F.Paste")
			(net "SMB_RT_CPU1_P0_ROM_MUX_2D_SCL")
		)
		(pad "4" smd rect
			(at -0.64008 0.750062 90)
			(size 0.3048 0.5334)
			(layers "F.Cu" "F.Mask" "F.Paste")
			(net "SMB_RT_CPU1_P0_ROM_MUX_2D_SDA")
		)
		(pad "5" smd rect
			(at 0 0.839978)
			(size 0.3302 0.635)
			(layers "F.Cu" "F.Mask" "F.Paste")
			(net "GND")
		)
		(pad "6" smd rect
			(at 0.64008 0.750062 90)
			(size 0.3048 0.5334)
			(layers "F.Cu" "F.Mask" "F.Paste")
			(net "RT_ROM_MUX1_OE_N")
		)
		(pad "7" smd rect
			(at 0.64008 0.249936 90)
			(size 0.254 0.5334)
			(layers "F.Cu" "F.Mask" "F.Paste")
			(net "SMB_RT_CPU1_P0_ROM_R_SDA")
		)
		(pad "8" smd rect
			(at 0.64008 -0.249936 90)
			(size 0.254 0.5334)
			(layers "F.Cu" "F.Mask" "F.Paste")
			(net "SMB_RT_CPU1_P0_ROM_R_SCL")
		)
		(pad "9" smd rect
			(at 0.64008 -0.750062 90)
			(size 0.3048 0.5334)
			(layers "F.Cu" "F.Mask" "F.Paste")
			(net "FM_SMB_RT_ROM_MUX1_SEL")
		)
		(pad "10" smd rect
			(at 0 -0.839978)
			(size 0.3302 0.635)
			(layers "F.Cu" "F.Mask" "F.Paste")
			(net "P3V3_AUX")
		)
	)
)
